# T6G (Grand Teton) — schematic netlist excerpt (pin names and nets, part order shuffled) for the footprints in the layout excerpt that follows; sources: Cadence DE-HDL packaged netlist, KiCad conversion of 04192023_DAF0TMB3IC0_F0TG_MB_C_brd_V02_OCP.brd

D8001  Q_LED  IC  pkg SMLF  page 256 : A = LED_P12V_PSU_R1 ; C = GND
R2992  Q_RES  0 5% CHIP  pkg 0402LF  page 248 : A = SMB_BMC_GPU_EN ; B = SMB_BMC_GPU_EN_R3

(kicad_pcb
	(version 20260206)
	(generator "pcbnew")
	(generator_version "10.0")
	(general
		(thickness 1.6)
		(legacy_teardrops no)
	)
	(paper "A4")
	(title_block
		(title "04192023_DAF0TMB3IC0_F0TG_MB_C_brd_V02_OCP.brd")
		(comment 1 "Grand Teton / footprints 4072-4073 of 8354")
	)
	(layers
		(0 "F.Cu" signal "TOP")
		(4 "In1.Cu" signal "GND")
		(6 "In2.Cu" signal "IN1")
		(8 "In3.Cu" signal "GND1")
		(10 "In4.Cu" signal "IN2")
		(12 "In5.Cu" signal "GND2")
		(14 "In6.Cu" signal "IN3")
		(16 "In7.Cu" signal "GND3")
		(18 "In8.Cu" signal "VCC")
		(20 "In9.Cu" signal "VCC1")
		(22 "In10.Cu" signal "GND4")
		(24 "In11.Cu" signal "IN4")
		(26 "In12.Cu" signal "GND5")
		(28 "In13.Cu" signal "IN5")
		(30 "In14.Cu" signal "GND6")
		(32 "In15.Cu" signal "IN6")
		(34 "In16.Cu" signal "GND7")
		(2 "B.Cu" signal "BOTTOM")
		(9 "F.Adhes" user "F.Adhesive")
		(11 "B.Adhes" user "B.Adhesive")
		(13 "F.Paste" user "Package Geometry/Pastemask Top")
		(15 "B.Paste" user "Package Geometry/Pastemask Bottom")
		(5 "F.SilkS" user "Ref Des/Silkscreen Top")
		(7 "B.SilkS" user "Ref Des/Silkscreen Bottom")
		(1 "F.Mask" user "Board Geometry/Soldermask Top")
		(3 "B.Mask" user "Board Geometry/Soldermask Bottom")
		(17 "Dwgs.User" user "User.Drawings")
		(19 "Cmts.User" user "User.Comments")
		(21 "Eco1.User" user "User.Eco1")
		(23 "Eco2.User" user "User.Eco2")
		(25 "Edge.Cuts" user "Board Geometry/Outline")
		(27 "Margin" user)
		(31 "F.CrtYd" user "Package Geometry/Place Bound Top")
		(29 "B.CrtYd" user "Package Geometry/Place Bound Bottom")
		(35 "F.Fab" user "Ref Des/Assembly Top")
		(33 "B.Fab" user "Ref Des/Assembly Bottom")
	)
	(footprint ""
		(layer "F.Cu")
		(at 38.180772 -58.155332 90)
		(property "Reference" "D8001"
			(at -1.781556 1.402334 90)
			(unlocked yes)
			(layer "F.SilkS")
			(effects
				(font
					(size 0.7874 0.5842)
					(thickness 0.1524)
				)
				(justify left)
			)
		)
		(property "Value" ""
			(at 0 0 90)
			(layer "F.Fab")
			(effects
				(font
					(size 1.27 1.27)
				)
			)
		)
		(duplicate_pad_numbers_are_jumpers no)
		(fp_line
			(start 1.16078 -0.4826)
			(end 1.16078 0.4826)
			(stroke
				(width 0.1524)
				(type default)
			)
			(layer "F.SilkS")
		)
		(fp_line
			(start 1.03378 -0.4826)
			(end 1.03378 0.4826)
			(stroke
				(width 0.1524)
				(type default)
			)
			(layer "F.SilkS")
		)
		(fp_line
			(start 0.90678 -0.4826)
			(end 0.90678 0.4826)
			(stroke
				(width 0.1524)
				(type default)
			)
			(layer "F.SilkS")
		)
		(fp_line
			(start -0.64008 -0.4826)
			(end 1.16078 -0.4826)
			(stroke
				(width 0.1524)
				(type default)
			)
			(layer "F.SilkS")
		)
		(fp_line
			(start -0.79248 -0.4826)
			(end 1.03378 -0.4826)
			(stroke
				(width 0.1524)
				(type default)
			)
			(layer "F.SilkS")
		)
		(fp_line
			(start -0.89408 -0.4826)
			(end 0.90678 -0.4826)
			(stroke
				(width 0.1524)
				(type default)
			)
			(layer "F.SilkS")
		)
		(fp_line
			(start 1.16078 0.4826)
			(end -0.64008 0.4826)
			(stroke
				(width 0.1524)
				(type default)
			)
			(layer "F.SilkS")
		)
		(fp_line
			(start 1.03378 0.4826)
			(end -0.79248 0.4826)
			(stroke
				(width 0.1524)
				(type default)
			)
			(layer "F.SilkS")
		)
		(fp_line
			(start 0.90678 0.4826)
			(end -0.90678 0.4826)
			(stroke
				(width 0.1524)
				(type default)
			)
			(layer "F.SilkS")
		)
		(fp_line
			(start -0.90678 0.4826)
			(end -0.90678 -0.4699)
			(stroke
				(width 0.1524)
				(type default)
			)
			(layer "F.SilkS")
		)
		(fp_line
			(start 0.499872 -0.249936)
			(end 0.499872 0.249936)
			(stroke
				(width 0.1)
				(type default)
			)
			(layer "F.Fab")
		)
		(fp_line
			(start -0.499872 -0.249936)
			(end 0.499872 -0.249936)
			(stroke
				(width 0.1)
				(type default)
			)
			(layer "F.Fab")
		)
		(fp_line
			(start 0.499872 0.249936)
			(end -0.499872 0.249936)
			(stroke
				(width 0.1)
				(type default)
			)
			(layer "F.Fab")
		)
		(fp_line
			(start -0.499872 0.249936)
			(end -0.499872 -0.249936)
			(stroke
				(width 0.1)
				(type default)
			)
			(layer "F.Fab")
		)
		(pad "A" smd rect
			(at -0.47498 0 90)
			(size 0.6096 0.7112)
			(layers "F.Cu" "F.Mask" "F.Paste")
			(net "LED_P12V_PSU_R1")
		)
		(pad "C" smd rect
			(at 0.47498 0 90)
			(size 0.6096 0.7112)
			(layers "F.Cu" "F.Mask" "F.Paste")
			(net "GND")
		)
	)
	(footprint ""
		(layer "F.Cu")
		(at 34.103818 -436.433214 180)
		(property "Reference" "R2992"
			(at 0 0 180)
			(layer "F.SilkS")
			(hide yes)
			(effects
				(font
					(size 1.27 1.27)
				)
			)
		)
		(property "Value" ""
			(at 0 0 180)
			(layer "F.Fab")
			(effects
				(font
					(size 1.27 1.27)
				)
			)
		)
		(duplicate_pad_numbers_are_jumpers no)
		(fp_line
			(start 0.7874 0.4064)
			(end -0.7874 0.4064)
			(stroke
				(width 0.1524)
				(type default)
			)
			(layer "F.SilkS")
		)
		(fp_line
			(start 0.7874 -0.4064)
			(end 0.7874 0.4064)
			(stroke
				(width 0.1524)
				(type default)
			)
			(layer "F.SilkS")
		)
		(fp_line
			(start -0.7874 0.4064)
			(end -0.7874 -0.4064)
			(stroke
				(width 0.1524)
				(type default)
			)
			(layer "F.SilkS")
		)
		(fp_line
			(start -0.7874 -0.4064)
			(end 0.7874 -0.4064)
			(stroke
				(width 0.1524)
				(type default)
			)
			(layer "F.SilkS")
		)
		(fp_line
			(start 0.67945 0.3048)
			(end 0.120396 0.3048)
			(stroke
				(width 0.1)
				(type default)
			)
			(layer "F.Fab")
		)
		(fp_line
			(start 0.67945 -0.3048)
			(end 0.67945 0.3048)
			(stroke
				(width 0.1)
				(type default)
			)
			(layer "F.Fab")
		)
		(fp_line
			(start 0.12065 -0.2794)
			(end 0.12065 -0.3048)
			(stroke
				(width 0.1)
				(type default)
			)
			(layer "F.Fab")
		)
		(fp_line
			(start 0.12065 -0.3048)
			(end 0.67945 -0.3048)
			(stroke
				(width 0.1)
				(type default)
			)
			(layer "F.Fab")
		)
		(fp_line
			(start 0.120396 0.3048)
			(end 0.120396 0.2794)
			(stroke
				(width 0.1)
				(type default)
			)
			(layer "F.Fab")
		)
		(fp_line
			(start 0.120396 0.2794)
			(end -0.12065 0.2794)
			(stroke
				(width 0.1)
				(type default)
			)
			(layer "F.Fab")
		)
		(fp_line
			(start -0.12065 0.3048)
			(end -0.67945 0.3048)
			(stroke
				(width 0.1)
				(type default)
			)
			(layer "F.Fab")
		)
		(fp_line
			(start -0.12065 0.2794)
			(end -0.12065 0.3048)
			(stroke
				(width 0.1)
				(type default)
			)
			(layer "F.Fab")
		)
		(fp_line
			(start -0.12065 -0.2794)
			(end 0.12065 -0.2794)
			(stroke
				(width 0.1)
				(type default)
			)
			(layer "F.Fab")
		)
		(fp_line
			(start -0.12065 -0.305054)
			(end -0.12065 -0.2794)
			(stroke
				(width 0.1)
				(type default)
			)
			(layer "F.Fab")
		)
		(fp_line
			(start -0.67945 0.3048)
			(end -0.67945 -0.305054)
			(stroke
				(width 0.1)
				(type default)
			)
			(layer "F.Fab")
		)
		(fp_line
			(start -0.67945 -0.305054)
			(end -0.12065 -0.305054)
			(stroke
				(width 0.1)
				(type default)
			)
			(layer "F.Fab")
		)
		(pad "1" smd circle
			(at -0.40005 0 180)
			(size 0 0)
			(layers "F.Cu" "F.Mask" "F.Paste")
			(net "SMB_BMC_GPU_EN")
		)
		(pad "2" smd circle
			(at 0.40005 0 180)
			(size 0 0)
			(layers "F.Cu" "F.Mask" "F.Paste")
			(net "SMB_BMC_GPU_EN_R3")
		)
	)
)
